(kicad_pcb
	(version 20260206)
	(generator "pcbnew")
	(generator_version "10.0")
	(general
		(thickness 1.6)
		(legacy_teardrops no)
	)
	(paper "A4")
	(title_block
		(title "01162023_DA0F0TEBIF0_F0T_Expander_BD_F_brd_V02_OCP.brd")
		(comment 1 "Grand Teton / footprints 1684-1690 of 9728")
	)
	(layers
		(0 "F.Cu" signal "TOP")
		(4 "In1.Cu" signal "GND")
		(6 "In2.Cu" signal "VCC")
		(8 "In3.Cu" signal "VCC1")
		(10 "In4.Cu" signal "GND1")
		(12 "In5.Cu" signal "IN1")
		(14 "In6.Cu" signal "GND2")
		(16 "In7.Cu" signal "IN2")
		(18 "In8.Cu" signal "GND3")
		(20 "In9.Cu" signal "IN3")
		(22 "In10.Cu" signal "GND4")
		(24 "In11.Cu" signal "IN4")
		(26 "In12.Cu" signal "GND5")
		(28 "In13.Cu" signal "IN5")
		(30 "In14.Cu" signal "GND6")
		(32 "In15.Cu" signal "IN6")
		(34 "In16.Cu" signal "GND7")
		(2 "B.Cu" signal "BOTTOM")
		(9 "F.Adhes" user "F.Adhesive")
		(11 "B.Adhes" user "B.Adhesive")
		(13 "F.Paste" user "Package Geometry/Pastemask Top")
		(15 "B.Paste" user "Package Geometry/Pastemask Bottom")
		(5 "F.SilkS" user "Ref Des/Silkscreen Top")
		(7 "B.SilkS" user "Ref Des/Silkscreen Bottom")
		(1 "F.Mask" user "Board Geometry/Soldermask Top")
		(3 "B.Mask" user "Board Geometry/Soldermask Bottom")
		(17 "Dwgs.User" user "User.Drawings")
		(19 "Cmts.User" user "User.Comments")
		(21 "Eco1.User" user "User.Eco1")
		(23 "Eco2.User" user "User.Eco2")
		(25 "Edge.Cuts" user "Board Geometry/Outline")
		(27 "Margin" user)
		(31 "F.CrtYd" user "Package Geometry/Place Bound Top")
		(29 "B.CrtYd" user "Package Geometry/Place Bound Bottom")
		(35 "F.Fab" user "Ref Des/Assembly Top")
		(33 "B.Fab" user "Ref Des/Assembly Bottom")
	)
	(footprint ""
		(layer "F.Cu")
		(at 269.19809 -369.947444)
		(property "Reference" "PR6615"
			(at 0 0 0)
			(layer "F.SilkS")
			(hide yes)
			(effects
				(font
					(size 1.27 1.27)
				)
			)
		)
		(property "Value" ""
			(at 0 0 0)
			(layer "F.Fab")
			(effects
				(font
					(size 1.27 1.27)
				)
			)
		)
		(duplicate_pad_numbers_are_jumpers no)
		(fp_line
			(start -0.7874 -0.4064)
			(end 0.7874 -0.4064)
			(stroke
				(width 0.1524)
				(type default)
			)
			(layer "F.SilkS")
		)
		(fp_line
			(start -0.7874 0.4064)
			(end -0.7874 -0.4064)
			(stroke
				(width 0.1524)
				(type default)
			)
			(layer "F.SilkS")
		)
		(fp_line
			(start 0.7874 -0.4064)
			(end 0.7874 0.4064)
			(stroke
				(width 0.1524)
				(type default)
			)
			(layer "F.SilkS")
		)
		(fp_line
			(start 0.7874 0.4064)
			(end -0.7874 0.4064)
			(stroke
				(width 0.1524)
				(type default)
			)
			(layer "F.SilkS")
		)
		(fp_line
			(start -0.67945 -0.305054)
			(end -0.12065 -0.305054)
			(stroke
				(width 0.1)
				(type default)
			)
			(layer "F.Fab")
		)
		(fp_line
			(start -0.67945 0.3048)
			(end -0.67945 -0.305054)
			(stroke
				(width 0.1)
				(type default)
			)
			(layer "F.Fab")
		)
		(fp_line
			(start -0.12065 -0.305054)
			(end -0.12065 -0.2794)
			(stroke
				(width 0.1)
				(type default)
			)
			(layer "F.Fab")
		)
		(fp_line
			(start -0.12065 -0.2794)
			(end 0.12065 -0.2794)
			(stroke
				(width 0.1)
				(type default)
			)
			(layer "F.Fab")
		)
		(fp_line
			(start -0.12065 0.2794)
			(end -0.12065 0.3048)
			(stroke
				(width 0.1)
				(type default)
			)
			(layer "F.Fab")
		)
		(fp_line
			(start -0.12065 0.3048)
			(end -0.67945 0.3048)
			(stroke
				(width 0.1)
				(type default)
			)
			(layer "F.Fab")
		)
		(fp_line
			(start 0.120396 0.2794)
			(end -0.12065 0.2794)
			(stroke
				(width 0.1)
				(type default)
			)
			(layer "F.Fab")
		)
		(fp_line
			(start 0.120396 0.3048)
			(end 0.120396 0.2794)
			(stroke
				(width 0.1)
				(type default)
			)
			(layer "F.Fab")
		)
		(fp_line
			(start 0.12065 -0.3048)
			(end 0.67945 -0.3048)
			(stroke
				(width 0.1)
				(type default)
			)
			(layer "F.Fab")
		)
		(fp_line
			(start 0.12065 -0.2794)
			(end 0.12065 -0.3048)
			(stroke
				(width 0.1)
				(type default)
			)
			(layer "F.Fab")
		)
		(fp_line
			(start 0.67945 -0.3048)
			(end 0.67945 0.3048)
			(stroke
				(width 0.1)
				(type default)
			)
			(layer "F.Fab")
		)
		(fp_line
			(start 0.67945 0.3048)
			(end 0.120396 0.3048)
			(stroke
				(width 0.1)
				(type default)
			)
			(layer "F.Fab")
		)
		(pad "1" smd circle
			(at -0.40005 0)
			(size 0 0)
			(layers "F.Cu" "F.Mask" "F.Paste")
			(net "LTC4282_TEMP_R_D-")
		)
		(pad "2" smd circle
			(at 0.40005 0)
			(size 0 0)
			(layers "F.Cu" "F.Mask" "F.Paste")
			(net "LTC4282_TEMP_D-")
		)
	)
	(footprint ""
		(layer "F.Cu")
		(at 7.320026 -20.72005)
		(property "Reference" "H127"
			(at -1.133602 2.425954 0)
			(unlocked yes)
			(layer "B.SilkS")
			(effects
				(font
					(size 0.7874 0.5842)
					(thickness 0.1524)
				)
				(justify left mirror)
			)
		)
		(property "Value" ""
			(at 0 0 0)
			(layer "F.Fab")
			(effects
				(font
					(size 1.27 1.27)
				)
			)
		)
		(duplicate_pad_numbers_are_jumpers no)
		(pad "1" thru_hole rect
			(at 0 0)
			(size 4.2164 5.0038)
			(drill 2.0066
				(offset 0.099822 0)
			)
			(layers "*.Cu" "*.Mask")
			(remove_unused_layers no)
			(net "Net_8536")
			(clearance -0.8509)
			(padstack
				(mode front_inner_back)
				(layer "Inner"
					(shape circle)
					(size 4.0132 4.0132)
					(clearance -0.7493)
				)
				(layer "B.Cu"
					(shape circle)
					(size 4.0132 4.0132)
					(clearance -0.7493)
				)
			)
		)
	)
	(footprint ""
		(layer "F.Cu")
		(at 6.709156 -27.04973 180)
		(property "Reference" "C2764"
			(at 0 0 180)
			(layer "F.SilkS")
			(hide yes)
			(effects
				(font
					(size 1.27 1.27)
				)
			)
		)
		(property "Value" ""
			(at 0 0 180)
			(layer "F.Fab")
			(effects
				(font
					(size 1.27 1.27)
				)
			)
		)
		(duplicate_pad_numbers_are_jumpers no)
		(fp_line
			(start 0.7874 0.4064)
			(end -0.7874 0.4064)
			(stroke
				(width 0.1524)
				(type default)
			)
			(layer "F.SilkS")
		)
		(fp_line
			(start 0.7874 -0.4064)
			(end 0.7874 0.4064)
			(stroke
				(width 0.1524)
				(type default)
			)
			(layer "F.SilkS")
		)
		(fp_line
			(start -0.7874 0.4064)
			(end -0.7874 -0.4064)
			(stroke
				(width 0.1524)
				(type default)
			)
			(layer "F.SilkS")
		)
		(fp_line
			(start -0.7874 -0.4064)
			(end 0.7874 -0.4064)
			(stroke
				(width 0.1524)
				(type default)
			)
			(layer "F.SilkS")
		)
		(fp_line
			(start 0.67945 0.3048)
			(end 0.120396 0.3048)
			(stroke
				(width 0.1)
				(type default)
			)
			(layer "F.Fab")
		)
		(fp_line
			(start 0.67945 -0.3048)
			(end 0.67945 0.3048)
			(stroke
				(width 0.1)
				(type default)
			)
			(layer "F.Fab")
		)
		(fp_line
			(start 0.12065 -0.2794)
			(end 0.12065 -0.3048)
			(stroke
				(width 0.1)
				(type default)
			)
			(layer "F.Fab")
		)
		(fp_line
			(start 0.12065 -0.3048)
			(end 0.67945 -0.3048)
			(stroke
				(width 0.1)
				(type default)
			)
			(layer "F.Fab")
		)
		(fp_line
			(start 0.120396 0.3048)
			(end 0.120396 0.2794)
			(stroke
				(width 0.1)
				(type default)
			)
			(layer "F.Fab")
		)
		(fp_line
			(start 0.120396 0.2794)
			(end -0.12065 0.2794)
			(stroke
				(width 0.1)
				(type default)
			)
			(layer "F.Fab")
		)
		(fp_line
			(start -0.12065 0.3048)
			(end -0.67945 0.3048)
			(stroke
				(width 0.1)
				(type default)
			)
			(layer "F.Fab")
		)
		(fp_line
			(start -0.12065 0.2794)
			(end -0.12065 0.3048)
			(stroke
				(width 0.1)
				(type default)
			)
			(layer "F.Fab")
		)
		(fp_line
			(start -0.12065 -0.2794)
			(end 0.12065 -0.2794)
			(stroke
				(width 0.1)
				(type default)
			)
			(layer "F.Fab")
		)
		(fp_line
			(start -0.12065 -0.305054)
			(end -0.12065 -0.2794)
			(stroke
				(width 0.1)
				(type default)
			)
			(layer "F.Fab")
		)
		(fp_line
			(start -0.67945 0.3048)
			(end -0.67945 -0.305054)
			(stroke
				(width 0.1)
				(type default)
			)
			(layer "F.Fab")
		)
		(fp_line
			(start -0.67945 -0.305054)
			(end -0.12065 -0.305054)
			(stroke
				(width 0.1)
				(type default)
			)
			(layer "F.Fab")
		)
		(pad "1" smd circle
			(at -0.40005 0 180)
			(size 0 0)
			(layers "F.Cu" "F.Mask" "F.Paste")
			(net "PRSNT_SSD0_R_N")
		)
		(pad "2" smd circle
			(at 0.40005 0 180)
			(size 0 0)
			(layers "F.Cu" "F.Mask" "F.Paste")
			(net "GND")
		)
	)
	(footprint ""
		(layer "F.Cu")
		(at 100.646992 -54.3941)
		(property "Reference" "PU36"
			(at -1.743964 2.828798 0)
			(unlocked yes)
			(layer "F.SilkS")
			(effects
				(font
					(size 0.7874 0.5842)
					(thickness 0.1524)
				)
				(justify left)
			)
		)
		(property "Value" ""
			(at 0 0 0)
			(layer "F.Fab")
			(effects
				(font
					(size 1.27 1.27)
				)
			)
		)
		(duplicate_pad_numbers_are_jumpers no)
		(fp_line
			(start -1.943608 -1.549908)
			(end 1.943608 -1.549908)
			(stroke
				(width 0.1524)
				(type default)
			)
			(layer "F.SilkS")
		)
		(fp_line
			(start -1.943608 1.549908)
			(end -1.943608 -1.549908)
			(stroke
				(width 0.1524)
				(type default)
			)
			(layer "F.SilkS")
		)
		(fp_line
			(start 1.943608 -1.549908)
			(end 1.943608 1.549908)
			(stroke
				(width 0.1524)
				(type default)
			)
			(layer "F.SilkS")
		)
		(fp_line
			(start 1.943608 1.549908)
			(end -1.943608 1.549908)
			(stroke
				(width 0.1524)
				(type default)
			)
			(layer "F.SilkS")
		)
		(fp_poly
			(pts
				(xy -2.019808 -1.549908) (xy -1.257808 -1.549908) (xy -1.257808 -1.880108) (xy -2.019808 -1.880108)
			)
			(stroke
				(width 0)
				(type default)
			)
			(fill yes)
			(layer "F.SilkS")
		)
		(fp_line
			(start -1.549908 -1.549908)
			(end 1.549908 -1.549908)
			(stroke
				(width 0.1)
				(type default)
			)
			(layer "F.Fab")
		)
		(fp_line
			(start -1.549908 1.549908)
			(end -1.549908 -1.549908)
			(stroke
				(width 0.1)
				(type default)
			)
			(layer "F.Fab")
		)
		(fp_line
			(start 1.549908 -1.549908)
			(end 1.549908 1.549908)
			(stroke
				(width 0.1)
				(type default)
			)
			(layer "F.Fab")
		)
		(fp_line
			(start 1.549908 1.549908)
			(end -1.549908 1.549908)
			(stroke
				(width 0.1)
				(type default)
			)
			(layer "F.Fab")
		)
		(fp_poly
			(pts
				(xy -2.019808 -1.549908) (xy -1.257808 -1.549908) (xy -1.257808 -1.880108) (xy -2.019808 -1.880108)
			)
			(stroke
				(width 0)
				(type default)
			)
			(fill yes)
			(layer "F.Fab")
		)
		(pad "1" smd rect
			(at -1.500124 -1.249934 270)
			(size 0.2794 0.6096)
			(layers "F.Cu" "F.Mask" "F.Paste")
			(net "P12V_SSD3_R")
		)
		(pad "2" smd rect
			(at -1.500124 -0.750062 270)
			(size 0.2794 0.6096)
			(layers "F.Cu" "F.Mask" "F.Paste")
			(net "P12V_SSD3_R")
		)
		(pad "3" smd rect
			(at -1.500124 -0.249936 270)
			(size 0.2794 0.6096)
			(layers "F.Cu" "F.Mask" "F.Paste")
			(net "P12V_SSD3_R")
		)
		(pad "4" smd rect
			(at -1.500124 0.249936 270)
			(size 0.2794 0.6096)
			(layers "F.Cu" "F.Mask" "F.Paste")
			(net "P12V_SSD3_R")
		)
		(pad "5" smd rect
			(at -1.500124 0.750062 270)
			(size 0.2794 0.6096)
			(layers "F.Cu" "F.Mask" "F.Paste")
			(net "P12V_SSD3_R")
		)
		(pad "6" smd rect
			(at -1.500124 1.249934 270)
			(size 0.2794 0.6096)
			(layers "F.Cu" "F.Mask" "F.Paste")
			(net "GND")
		)
		(pad "7" smd rect
			(at 1.500124 1.249934 270)
			(size 0.2794 0.6096)
			(layers "F.Cu" "F.Mask" "F.Paste")
			(net "P12V_SSD3_SS")
		)
		(pad "8" smd rect
			(at 1.500124 0.750062 270)
			(size 0.2794 0.6096)
			(layers "F.Cu" "F.Mask" "F.Paste")
			(net "PWRGD_P12V_SSD3")
		)
		(pad "9" smd rect
			(at 1.500124 0.249936 270)
			(size 0.2794 0.6096)
			(layers "F.Cu" "F.Mask" "F.Paste")
			(net "P12V_SSD3_OCP")
		)
		(pad "10" smd rect
			(at 1.500124 -0.249936 270)
			(size 0.2794 0.6096)
			(layers "F.Cu" "F.Mask" "F.Paste")
			(net "P5V_AUX")
		)
		(pad "11" smd rect
			(at 1.500124 -0.750062 270)
			(size 0.2794 0.6096)
			(layers "F.Cu" "F.Mask" "F.Paste")
			(net "SSD3_PWR_EN_R")
		)
		(pad "12" smd rect
			(at 1.500124 -1.249934 270)
			(size 0.2794 0.6096)
			(layers "F.Cu" "F.Mask" "F.Paste")
			(net "P12V_AUX")
		)
		(pad "13" smd rect
			(at 0 0)
			(size 1.9812 2.7178)
			(layers "F.Cu" "F.Mask" "F.Paste")
			(net "P12V_AUX")
		)
		(zone
			(layer "F.Cu")
			(hatch none 0.5)
			(connect_pads
				(clearance 0)
			)
			(min_thickness 0.25)
			(keepout
				(tracks not_allowed)
				(vias allowed)
				(pads allowed)
				(copperpour not_allowed)
				(footprints allowed)
			)
			(placement
				(enabled no)
				(sheetname "")
			)
			(fill
				(thermal_gap 0.5)
				(thermal_bridge_width 0.5)
				(island_removal_mode 0)
			)
			(polygon
				(pts
					(xy 101.789992 -55.9435) (xy 101.789992 -55.8165) (xy 101.789992 -52.8447) (xy 101.789992 -52.844192)
					(xy 99.503992 -52.844192) (xy 99.503992 -52.8447) (xy 99.503992 -52.9717) (xy 99.503992 -54.3941)
					(xy 99.605592 -54.3941) (xy 99.605592 -52.9717) (xy 101.688392 -52.9717) (xy 101.688392 -55.8165)
					(xy 99.605592 -55.8165) (xy 99.605592 -54.4195) (xy 99.503992 -54.4195) (xy 99.503992 -55.8165)
					(xy 99.503992 -55.9435) (xy 99.503992 -55.944008) (xy 101.789992 -55.944008)
				)
			)
		)
	)
	(footprint ""
		(layer "F.Cu")
		(at 196.119242 -129.880106 180)
		(property "Reference" "C235"
			(at 0 0 180)
			(layer "F.SilkS")
			(hide yes)
			(effects
				(font
					(size 1.27 1.27)
				)
			)
		)
		(property "Value" ""
			(at 0 0 180)
			(layer "F.Fab")
			(effects
				(font
					(size 1.27 1.27)
				)
			)
		)
		(duplicate_pad_numbers_are_jumpers no)
		(fp_line
			(start 0.299974 0.150114)
			(end -0.299974 0.150114)
			(stroke
				(width 0.1)
				(type default)
			)
			(layer "F.Fab")
		)
		(fp_line
			(start 0.299974 -0.150114)
			(end 0.299974 0.150114)
			(stroke
				(width 0.1)
				(type default)
			)
			(layer "F.Fab")
		)
		(fp_line
			(start -0.299974 0.150114)
			(end -0.299974 -0.150114)
			(stroke
				(width 0.1)
				(type default)
			)
			(layer "F.Fab")
		)
		(fp_line
			(start -0.299974 -0.150114)
			(end 0.299974 -0.150114)
			(stroke
				(width 0.1)
				(type default)
			)
			(layer "F.Fab")
		)
		(pad "1" smd rect
			(at -0.2667 0 180)
			(size 0.3048 0.381)
			(layers "F.Cu" "F.Mask" "F.Paste")
			(net "P5E_PEX1_STN0_TX_DN<4>")
		)
		(pad "2" smd rect
			(at 0.2667 0 180)
			(size 0.3048 0.381)
			(layers "F.Cu" "F.Mask" "F.Paste")
			(net "P5E_PEX1_STN0_TX_C_DN<4>")
		)
	)
	(footprint ""
		(layer "F.Cu")
		(at 258.369562 -215.56472)
		(property "Reference" "C2848"
			(at 0 0 0)
			(layer "F.SilkS")
			(hide yes)
			(effects
				(font
					(size 1.27 1.27)
				)
			)
		)
		(property "Value" ""
			(at 0 0 0)
			(layer "F.Fab")
			(effects
				(font
					(size 1.27 1.27)
				)
			)
		)
		(duplicate_pad_numbers_are_jumpers no)
		(fp_line
			(start -0.7874 -0.4064)
			(end 0.7874 -0.4064)
			(stroke
				(width 0.1524)
				(type default)
			)
			(layer "F.SilkS")
		)
		(fp_line
			(start -0.7874 0.4064)
			(end -0.7874 -0.4064)
			(stroke
				(width 0.1524)
				(type default)
			)
			(layer "F.SilkS")
		)
		(fp_line
			(start 0.7874 -0.4064)
			(end 0.7874 0.4064)
			(stroke
				(width 0.1524)
				(type default)
			)
			(layer "F.SilkS")
		)
		(fp_line
			(start 0.7874 0.4064)
			(end -0.7874 0.4064)
			(stroke
				(width 0.1524)
				(type default)
			)
			(layer "F.SilkS")
		)
		(fp_line
			(start -0.67945 -0.305054)
			(end -0.12065 -0.305054)
			(stroke
				(width 0.1)
				(type default)
			)
			(layer "F.Fab")
		)
		(fp_line
			(start -0.67945 0.3048)
			(end -0.67945 -0.305054)
			(stroke
				(width 0.1)
				(type default)
			)
			(layer "F.Fab")
		)
		(fp_line
			(start -0.12065 -0.305054)
			(end -0.12065 -0.2794)
			(stroke
				(width 0.1)
				(type default)
			)
			(layer "F.Fab")
		)
		(fp_line
			(start -0.12065 -0.2794)
			(end 0.12065 -0.2794)
			(stroke
				(width 0.1)
				(type default)
			)
			(layer "F.Fab")
		)
		(fp_line
			(start -0.12065 0.2794)
			(end -0.12065 0.3048)
			(stroke
				(width 0.1)
				(type default)
			)
			(layer "F.Fab")
		)
		(fp_line
			(start -0.12065 0.3048)
			(end -0.67945 0.3048)
			(stroke
				(width 0.1)
				(type default)
			)
			(layer "F.Fab")
		)
		(fp_line
			(start 0.120396 0.2794)
			(end -0.12065 0.2794)
			(stroke
				(width 0.1)
				(type default)
			)
			(layer "F.Fab")
		)
		(fp_line
			(start 0.120396 0.3048)
			(end 0.120396 0.2794)
			(stroke
				(width 0.1)
				(type default)
			)
			(layer "F.Fab")
		)
		(fp_line
			(start 0.12065 -0.3048)
			(end 0.67945 -0.3048)
			(stroke
				(width 0.1)
				(type default)
			)
			(layer "F.Fab")
		)
		(fp_line
			(start 0.12065 -0.2794)
			(end 0.12065 -0.3048)
			(stroke
				(width 0.1)
				(type default)
			)
			(layer "F.Fab")
		)
		(fp_line
			(start 0.67945 -0.3048)
			(end 0.67945 0.3048)
			(stroke
				(width 0.1)
				(type default)
			)
			(layer "F.Fab")
		)
		(fp_line
			(start 0.67945 0.3048)
			(end 0.120396 0.3048)
			(stroke
				(width 0.1)
				(type default)
			)
			(layer "F.Fab")
		)
		(pad "1" smd circle
			(at -0.40005 0)
			(size 0 0)
			(layers "F.Cu" "F.Mask" "F.Paste")
			(net "P5V_AUX")
		)
		(pad "2" smd circle
			(at 0.40005 0)
			(size 0 0)
			(layers "F.Cu" "F.Mask" "F.Paste")
			(net "GND")
		)
	)
	(footprint ""
		(layer "F.Cu")
		(at 82.661506 -151.596852 180)
		(property "Reference" "C6"
			(at 0 0 180)
			(layer "F.SilkS")
			(hide yes)
			(effects
				(font
					(size 1.27 1.27)
				)
			)
		)
		(property "Value" ""
			(at 0 0 180)
			(layer "F.Fab")
			(effects
				(font
					(size 1.27 1.27)
				)
			)
		)
		(duplicate_pad_numbers_are_jumpers no)
		(fp_line
			(start 0.299974 0.150114)
			(end -0.299974 0.150114)
			(stroke
				(width 0.1)
				(type default)
			)
			(layer "F.Fab")
		)
		(fp_line
			(start 0.299974 -0.150114)
			(end 0.299974 0.150114)
			(stroke
				(width 0.1)
				(type default)
			)
			(layer "F.Fab")
		)
		(fp_line
			(start -0.299974 0.150114)
			(end -0.299974 -0.150114)
			(stroke
				(width 0.1)
				(type default)
			)
			(layer "F.Fab")
		)
		(fp_line
			(start -0.299974 -0.150114)
			(end 0.299974 -0.150114)
			(stroke
				(width 0.1)
				(type default)
			)
			(layer "F.Fab")
		)
		(pad "1" smd rect
			(at -0.2667 0 180)
			(size 0.3048 0.381)
			(layers "F.Cu" "F.Mask" "F.Paste")
			(net "P5E_PEX0_STN0_TX_DN<13>")
		)
		(pad "2" smd rect
			(at 0.2667 0 180)
			(size 0.3048 0.381)
			(layers "F.Cu" "F.Mask" "F.Paste")
			(net "P5E_PEX0_STN0_TX_C_DN<13>")
		)
	)
)
